(kicad_pcb
	(version 20221018)
	(generator pcbnew)
	(general
    (thickness 1.586)
  )
	(paper "A4")
	(title_block
    (date "2024-03-26")
    (rev "1.1.3")
		(comment 9 "footprints 34-37 of 146")
	)
	(layers
    (0 "F.Cu" signal)
    (1 "In1.Cu" power)
    (2 "In2.Cu" power)
    (31 "B.Cu" signal)
    (32 "B.Adhes" user "B.Adhesive")
    (33 "F.Adhes" user "F.Adhesive")
    (34 "B.Paste" user)
    (35 "F.Paste" user)
    (36 "B.SilkS" user "B.Silkscreen")
    (37 "F.SilkS" user "F.Silkscreen")
    (38 "B.Mask" user)
    (39 "F.Mask" user)
    (40 "Dwgs.User" user "User.Drawings")
    (41 "Cmts.User" user "User.Comments")
    (42 "Eco1.User" user "User.Eco1")
    (43 "Eco2.User" user "User.Eco2")
    (44 "Edge.Cuts" user)
    (45 "Margin" user)
    (46 "B.CrtYd" user "B.Courtyard")
    (47 "F.CrtYd" user "F.Courtyard")
    (48 "B.Fab" user)
    (49 "F.Fab" user)
  )
	(footprint "scalenode-cm4-baseboard-footprints:R_0402_1005Metric" (layer "F.Cu")
    (at 158.93 74.66 90)
    (descr "Resistor SMD 0402")
    (tags "resistor SMD 0402")
    (property "Author" "Antmicro")
    (property "License" "Apache-2.0")
    (property "MPN" "CR0402-FX-1101GLF")
    (property "Manufacturer" "Bourns")
    (property "Sheetfile" "interfaces.kicad_sch")
    (property "Sheetname" "Interfaces")
    (property "Tolerance" "1%")
    (property "Val" "1k1")
    (property "ki_description" "1k1 resistor in 0402 package with 1% tolerance")
    (attr smd)
    (fp_text reference "R16" (at -1.05 -0.63 270) (layer "F.SilkS")
        (effects (font (size 0.7 0.7) (thickness 0.15)) (justify left bottom))
    )
    (fp_text value "R_1k1_0402" (at 0 1.4 90) (layer "F.Fab")
        (effects (font (size 0.7 0.7) (thickness 0.15)) (justify left bottom))
    )
    (fp_text user "Author: Antmicro" (at -0.95 4.169 90) (layer "F.Fab") hide
        (effects (font (size 0.7 0.7) (thickness 0.15)) (justify left bottom))
    )
    (fp_text user "License: Apache-2.0" (at -0.95 5.169 90) (layer "F.Fab") hide
        (effects (font (size 0.7 0.7) (thickness 0.15)) (justify left bottom))
    )
    (fp_text user "${REFERENCE}" (at -0.95 3.168 90) (layer "F.Fab") hide
        (effects (font (size 0.7 0.7) (thickness 0.15)) (justify left bottom))
    )
    (fp_rect (start -0.95 -0.48) (end 0.95 0.48)
      (stroke (width 0.05) (type solid)) (fill none) (layer "F.CrtYd"))
    (fp_rect (start -0.5 -0.25) (end 0.5 0.25)
      (stroke (width 0.15) (type solid)) (fill none) (layer "F.Fab"))
    (pad "1" smd roundrect (at -0.485 0 90) (size 0.59 0.64) (layers "F.Cu" "F.Paste" "F.Mask") (roundrect_rratio 0.25)
      (net 95 "USBOTG_ID") (pintype "passive"))
    (pad "2" smd roundrect (at 0.485 0 90) (size 0.59 0.64) (layers "F.Cu" "F.Paste" "F.Mask") (roundrect_rratio 0.25)
      (net 244 "PROG_MODE") (pintype "passive"))
  )
	(footprint "scalenode-cm4-baseboard-footprints:MSOP-10_W3mm" (layer "F.Cu")
    (at 161.4 77.8 -90)
    (property "Author" "Antmicro")
    (property "License" "Apache-2.0")
    (property "MPN" "TS3USB30EDGSR")
    (property "Manufacturer" "Texas Instruments")
    (property "Sheetfile" "interfaces.kicad_sch")
    (property "Sheetname" "Interfaces")
    (attr smd)
    (fp_text reference "U5" (at 0 -4.401 -90) (layer "F.SilkS")
        (effects (font (size 0.7 0.7) (thickness 0.15)) (justify left bottom))
    )
    (fp_text value "TS3USB30EDGSR" (at 0 4.799 -90) (layer "F.Fab")
        (effects (font (size 0.7 0.7) (thickness 0.15)) (justify left bottom))
    )
    (fp_text user "License: Apache-2.0" (at -2.351 7.999 -90) (layer "F.Fab") hide
        (effects (font (size 0.7 0.7) (thickness 0.15)) (justify left bottom))
    )
    (fp_text user "${REFERENCE}" (at -2.351 9.198 -90) (layer "F.Fab") hide
        (effects (font (size 0.7 0.7) (thickness 0.15)) (justify left bottom))
    )
    (fp_text user "Author: Antmicro" (at -2.351 6.799 -90) (layer "F.Fab") hide
        (effects (font (size 0.7 0.7) (thickness 0.15)) (justify left bottom))
    )
    (fp_text user "REF**" (at 0 0 -90) (layer "F.Fab") hide
        (effects (font (size 0.5 0.5) (thickness 0.05)))
    )
    (fp_line (start -1.601 -1.601) (end -1.301 -1.601)
      (stroke (width 0.15) (type solid)) (layer "F.SilkS"))
    (fp_line (start -1.601 -1.301) (end -1.601 -1.601)
      (stroke (width 0.15) (type solid)) (layer "F.SilkS"))
    (fp_line (start -1.601 1.3) (end -1.301 1.6)
      (stroke (width 0.15) (type solid)) (layer "F.SilkS"))
    (fp_line (start -1.301 1.6) (end -1.301 2.797)
      (stroke (width 0.15) (type solid)) (layer "F.SilkS"))
    (fp_line (start 1.3 -1.601) (end 1.6 -1.601)
      (stroke (width 0.15) (type solid)) (layer "F.SilkS"))
    (fp_line (start 1.6 -1.601) (end 1.6 -1.301)
      (stroke (width 0.15) (type solid)) (layer "F.SilkS"))
    (fp_line (start 1.6 1.3) (end 1.6 1.6)
      (stroke (width 0.15) (type solid)) (layer "F.SilkS"))
    (fp_line (start 1.6 1.6) (end 1.3 1.6)
      (stroke (width 0.15) (type solid)) (layer "F.SilkS"))
    (fp_circle (center -1.6 1.7) (end -1.55 1.7)
      (stroke (width 0.15) (type solid)) (fill solid) (layer "F.SilkS"))
    (fp_line (start -1.75 -3.19) (end 1.71 -3.19)
      (stroke (width 0.05) (type solid)) (layer "F.CrtYd"))
    (fp_line (start -1.75 3.18) (end -1.75 -3.19)
      (stroke (width 0.05) (type solid)) (layer "F.CrtYd"))
    (fp_line (start -1.75 3.18) (end 1.71 3.18)
      (stroke (width 0.05) (type solid)) (layer "F.CrtYd"))
    (fp_line (start 1.71 -3.19) (end 1.71 3.18)
      (stroke (width 0.05) (type solid)) (layer "F.CrtYd"))
    (fp_line (start -1.45 -1.45) (end -1.45 1.1)
      (stroke (width 0.15) (type solid)) (layer "F.Fab"))
    (fp_line (start -1.45 -1.45) (end 1.449 -1.45)
      (stroke (width 0.15) (type solid)) (layer "F.Fab"))
    (fp_line (start -1.45 1.1) (end -1.101 1.449)
      (stroke (width 0.15) (type solid)) (layer "F.Fab"))
    (fp_line (start -1.101 1.449) (end 1.449 1.449)
      (stroke (width 0.15) (type solid)) (layer "F.Fab"))
    (fp_line (start 1.449 -1.45) (end 1.449 1.449)
      (stroke (width 0.15) (type solid)) (layer "F.Fab"))
    (pad "1" smd rect (at -1 2.201 270) (size 0.3 1.45) (layers "F.Cu" "F.Paste" "F.Mask")
      (net 95 "USBOTG_ID") (pinfunction "S") (pintype "input") (solder_mask_margin 0.05))
    (pad "2" smd rect (at -0.5 2.201 270) (size 0.3 1.45) (layers "F.Cu" "F.Paste" "F.Mask")
      (net 251 "/Interfaces/FTDI_USB_P") (pinfunction "D1+") (pintype "bidirectional") (solder_mask_margin 0.05))
    (pad "3" smd rect (at 0 2.201 270) (size 0.3 1.45) (layers "F.Cu" "F.Paste" "F.Mask")
      (net 25 "/Interfaces/RPi_USB_P") (pinfunction "D2+") (pintype "bidirectional") (solder_mask_margin 0.05))
    (pad "4" smd rect (at 0.496 2.201 270) (size 0.3 1.45) (layers "F.Cu" "F.Paste" "F.Mask")
      (net 236 "/Interfaces/CONN_USB_P") (pinfunction "D+") (pintype "bidirectional") (solder_mask_margin 0.05))
    (pad "5" smd rect (at 0.996 2.201 270) (size 0.3 1.45) (layers "F.Cu" "F.Paste" "F.Mask")
      (net 11 "GND") (pinfunction "GND") (pintype "power_in") (solder_mask_margin 0.05))
    (pad "6" smd rect (at 0.996 -2.202 270) (size 0.3 1.45) (layers "F.Cu" "F.Paste" "F.Mask")
      (net 235 "/Interfaces/CONN_USB_N") (pinfunction "D-") (pintype "bidirectional") (solder_mask_margin 0.05))
    (pad "7" smd rect (at 0.496 -2.202 270) (size 0.3 1.45) (layers "F.Cu" "F.Paste" "F.Mask")
      (net 24 "/Interfaces/RPi_USB_N") (pinfunction "D2-") (pintype "bidirectional") (solder_mask_margin 0.05))
    (pad "8" smd rect (at 0 -2.202 270) (size 0.3 1.45) (layers "F.Cu" "F.Paste" "F.Mask")
      (net 249 "/Interfaces/FTDI_USB_N") (pinfunction "D1-") (pintype "bidirectional") (solder_mask_margin 0.05))
    (pad "9" smd rect (at -0.5 -2.202 270) (size 0.3 1.45) (layers "F.Cu" "F.Paste" "F.Mask")
      (net 264 "Net-(U5-~{OE})") (pinfunction "~{OE}") (pintype "input") (solder_mask_margin 0.05))
    (pad "10" smd rect (at -1 -2.202 270) (size 0.3 1.45) (layers "F.Cu" "F.Paste" "F.Mask")
      (net 232 "3V3_RPi") (pinfunction "VCC") (pintype "power_in") (solder_mask_margin 0.05))
  )
	(footprint "scalenode-cm4-baseboard-footprints:USB-Micro-B_Receptacle_Molex_473460001" (layer "F.Cu")
    (at 77.05 87.373 -90)
    (descr "http://www.molex.com/pdm_docs/sd/473460001_sd.pdf")
    (property "Author" "Antmicro")
    (property "License" "Apache-2.0")
    (property "MPN" "473460001")
    (property "Manufacturer" "Molex")
    (property "Sheetfile" "interfaces.kicad_sch")
    (property "Sheetname" "Interfaces")
    (property "ki_description" "USB - micro B USB 2.0 Receptacle Connector 5 Position Surface Mount, Right Angle")
    (property "ki_keywords" "USB, MICRO, CONNECTOR, SMT, HORIZONTAL")
    (attr smd)
    (fp_text reference "J5" (at 5.202 1.8) (layer "F.SilkS")
        (effects (font (size 0.7 0.7) (thickness 0.15)) (justify left bottom))
    )
    (fp_text value "USB-Micro-B_Molex_473460001" (at -7.998 -0.05 -90) (layer "F.Fab")
        (effects (font (size 0.7 0.7) (thickness 0.15)) (justify left bottom))
    )
    (fp_text user "Author: Antmicro" (at -7.925 9.575 -90) (layer "F.Fab") hide
        (effects (font (size 0.7 0.7) (thickness 0.15)) (justify left bottom))
    )
    (fp_text user "License: Apache-2.0" (at -7.925 7.175 -90) (layer "F.Fab") hide
        (effects (font (size 0.7 0.7) (thickness 0.15)) (justify left bottom))
    )
    (fp_text user "${REFERENCE}" (at -7.925 5.975 -90) (layer "F.Fab") hide
        (effects (font (size 0.7 0.7) (thickness 0.15)) (justify left bottom))
    )
    (fp_line (start -4 -2.751) (end -4 -2.251)
      (stroke (width 0.15) (type solid)) (layer "F.SilkS"))
    (fp_line (start -4 -2.751) (end -3.5 -2.751)
      (stroke (width 0.15) (type solid)) (layer "F.SilkS"))
    (fp_line (start -4 2.698) (end -4 2.148)
      (stroke (width 0.15) (type solid)) (layer "F.SilkS"))
    (fp_line (start -4 2.698) (end -3.5 2.698)
      (stroke (width 0.15) (type solid)) (layer "F.SilkS"))
    (fp_line (start 3.999 -2.751) (end 3.499 -2.751)
      (stroke (width 0.15) (type solid)) (layer "F.SilkS"))
    (fp_line (start 3.999 -2.751) (end 3.999 -2.251)
      (stroke (width 0.15) (type solid)) (layer "F.SilkS"))
    (fp_line (start 3.999 2.698) (end 3.499 2.698)
      (stroke (width 0.15) (type solid)) (layer "F.SilkS"))
    (fp_line (start 3.999 2.698) (end 3.999 2.198)
      (stroke (width 0.15) (type solid)) (layer "F.SilkS"))
    (fp_circle (center -1.301 -3.601) (end -1.351 -3.601)
      (stroke (width 0.15) (type solid)) (fill solid) (layer "F.SilkS"))
    (fp_rect (start 4.236 2.946) (end -4.246 -3.23)
      (stroke (width 0.05) (type solid)) (fill none) (layer "F.CrtYd"))
    (fp_line (start -3.7745 -2.6995) (end -3.9755 -2.5005)
      (stroke (width 0.15) (type solid)) (layer "F.Fab"))
    (fp_rect (start 3.99 2.713) (end -3.992 -2.714)
      (stroke (width 0.15) (type solid)) (fill none) (layer "F.Fab"))
    (pad "1" smd rect (at -1.301 -2.376) (size 1.38 0.45) (layers "F.Cu" "F.Paste" "F.Mask")
      (net 27 "/Interfaces/VBus_Slave") (pinfunction "VBUS") (pintype "passive"))
    (pad "2" smd rect (at -0.652 -2.376) (size 1.38 0.45) (layers "F.Cu" "F.Paste" "F.Mask")
      (net 235 "/Interfaces/CONN_USB_N") (pinfunction "D-") (pintype "bidirectional"))
    (pad "3" smd rect (at -0.001 -2.376) (size 1.38 0.45) (layers "F.Cu" "F.Paste" "F.Mask")
      (net 236 "/Interfaces/CONN_USB_P") (pinfunction "D+") (pintype "bidirectional"))
    (pad "4" smd rect (at 0.652 -2.376) (size 1.38 0.45) (layers "F.Cu" "F.Paste" "F.Mask")
      (net 202 "unconnected-(J5-ID-Pad4)") (pinfunction "ID") (pintype "bidirectional+no_connect"))
    (pad "5" smd rect (at 1.3 -2.376) (size 1.38 0.45) (layers "F.Cu" "F.Paste" "F.Mask")
      (net 11 "GND") (pinfunction "GND") (pintype "power_in"))
    (pad "SH" smd rect (at -2.911 0.284) (size 1.9 2.375) (layers "F.Cu" "F.Paste" "F.Mask")
      (net 11 "GND") (pinfunction "SHIELD") (pintype "passive"))
    (pad "SH" smd rect (at -2.464 -2.016) (size 2.1 1.475) (layers "F.Cu" "F.Paste" "F.Mask")
      (net 11 "GND") (pinfunction "SHIELD") (pintype "passive"))
    (pad "SH" smd rect (at -0.836 0.284) (size 1.9 1.175) (layers "F.Cu" "F.Paste" "F.Mask")
      (net 11 "GND") (pinfunction "SHIELD") (pintype "passive"))
    (pad "SH" smd rect (at 0.836 0.284) (size 1.9 1.175) (layers "F.Cu" "F.Paste" "F.Mask")
      (net 11 "GND") (pinfunction "SHIELD") (pintype "passive"))
    (pad "SH" smd rect (at 2.463 -2.016) (size 2.1 1.475) (layers "F.Cu" "F.Paste" "F.Mask")
      (net 11 "GND") (pinfunction "SHIELD") (pintype "passive"))
    (pad "SH" smd rect (at 2.913 0.284) (size 1.9 2.375) (layers "F.Cu" "F.Paste" "F.Mask")
      (net 11 "GND") (pinfunction "SHIELD") (pintype "passive"))
  )
	(footprint "scalenode-cm4-baseboard-footprints:MP_Pad4.5mm_Drill2.2mm" (layer "F.Cu")
    (at 78.126 94.198)
    (property "Author" "Antmicro")
    (property "License" "Apache-2.0")
    (property "MPN" "")
    (property "Manufacturer" "")
    (property "Sheetfile" "expansion-connectors.kicad_sch")
    (property "Sheetname" "Expansion connectors")
    (property "exclude_from_bom" "")
    (property "ki_description" "Mechanical part")
    (property "ki_keywords" "MECHANICAL")
    (attr through_hole exclude_from_bom)
    (fp_text reference "MP1" (at 1.774 2.227) (layer "F.SilkS") hide
        (effects (font (size 0.7 0.7) (thickness 0.15)) (justify left bottom))
    )
    (fp_text value "MP_Pad4.5mm_Drill2.2mm" (at -0.153 -4.153) (layer "F.Fab")
        (effects (font (size 0.7 0.7) (thickness 0.15)) (justify left bottom))
    )
    (fp_text user "License: Apache-2.0" (at -0.178 8.425) (layer "F.Fab") hide
        (effects (font (size 0.7 0.7) (thickness 0.15)) (justify left bottom))
    )
    (fp_text user "Author: Antmicro" (at -0.178 7.225) (layer "F.Fab") hide
        (effects (font (size 0.7 0.7) (thickness 0.15)) (justify left bottom))
    )
    (fp_text user "${REFERENCE}" (at -0.178 6.025) (layer "F.Fab") hide
        (effects (font (size 0.7 0.7) (thickness 0.15)) (justify left bottom))
    )
    (pad "1" thru_hole circle (at 0 0) (size 4.5 4.5) (drill 2.2) (layers "*.Cu" "*.Mask")
      (net 229 "unconnected-(MP1-Pad1)") (pintype "passive+no_connect"))
  )
)
